(kicad_pcb
	(version 20260206)
	(generator "pcbnew")
	(generator_version "10.0")
	(general
		(thickness 1.6)
		(legacy_teardrops no)
	)
	(paper "A4")
	(title_block
		(title "peb — Lightning_PEB_BRD.brd")
		(comment 1 "Lightning (Wiwynn / Facebook NVMe JBOF) / footprint 432 of 2563 (GF9), pads 114-200 of 200")
	)
	(layers
		(0 "F.Cu" signal "TOP")
		(4 "In1.Cu" signal "L2GND")
		(6 "In2.Cu" signal "L3")
		(8 "In3.Cu" signal "L4VCC")
		(10 "In4.Cu" signal "L5VCC")
		(12 "In5.Cu" signal "L6")
		(14 "In6.Cu" signal "L7GND")
		(2 "B.Cu" signal "BOTTOM")
		(9 "F.Adhes" user "F.Adhesive")
		(11 "B.Adhes" user "B.Adhesive")
		(13 "F.Paste" user "Package Geometry/Pastemask Top")
		(15 "B.Paste" user "Package Geometry/Pastemask Bottom")
		(5 "F.SilkS" user "Ref Des/Silkscreen Top")
		(7 "B.SilkS" user "Ref Des/Silkscreen Bottom")
		(1 "F.Mask" user "Board Geometry/Soldermask Top")
		(3 "B.Mask" user "Board Geometry/Soldermask Bottom")
		(17 "Dwgs.User" user "User.Drawings")
		(19 "Cmts.User" user "User.Comments")
		(21 "Eco1.User" user "User.Eco1")
		(23 "Eco2.User" user "User.Eco2")
		(25 "Edge.Cuts" user "Board Geometry/Outline")
		(27 "Margin" user)
		(31 "F.CrtYd" user "Package Geometry/Place Bound Top")
		(29 "B.CrtYd" user "Package Geometry/Place Bound Bottom")
		(35 "F.Fab" user "Ref Des/Assembly Top")
		(33 "B.Fab" user "Ref Des/Assembly Bottom")
	)
	(footprint ""
		(layer "F.Cu")
		(at 181.30012 -226.70008 180)
		(property "Reference" "GF9"
			(at 0 0 180)
			(layer "F.SilkS")
			(hide yes)
			(effects
				(font
					(size 1.27 1.27)
				)
			)
		)
		(property "Value" "GF-200P-8-GP-U1"
			(at -43.1673 -7.6327 180)
			(unlocked yes)
			(layer "F.Fab")
			(hide yes)
			(effects
				(font
					(size 1.016 1.016)
					(thickness 0.1524)
				)
			)
		)
		(property "Device Type" "GF-200P-8-U1"
			(at -43.1673 -9.1567 180)
			(unlocked yes)
			(layer "F.Fab")
			(hide yes)
			(effects
				(font
					(size 1.016 1.016)
					(thickness 0.1524)
				)
			)
		)
		(duplicate_pad_numbers_are_jumpers no)
		(pad "B14" smd rect
			(at -25.999948 -0.7747 180)
			(size 0.5588 2.3114)
			(drill
				(offset 0 -0.381)
			)
			(layers "F.Cu" "F.Mask" "F.Paste")
			(net "SSD_PRSNT#12_R")
		)
		(pad "B15" smd rect
			(at -25.200102 -0.7747 180)
			(size 0.5588 2.3114)
			(drill
				(offset 0 -0.381)
			)
			(layers "F.Cu" "F.Mask" "F.Paste")
			(net "GND")
		)
		(pad "B16" smd rect
			(at -24.400002 -0.7747 180)
			(size 0.5588 2.3114)
			(drill
				(offset 0 -0.381)
			)
			(layers "F.Cu" "F.Mask" "F.Paste")
			(net "PCIE_RX_N40")
		)
		(pad "B17" smd rect
			(at -23.599902 -0.7747 180)
			(size 0.5588 2.3114)
			(drill
				(offset 0 -0.381)
			)
			(layers "F.Cu" "F.Mask" "F.Paste")
			(net "PCIE_RX_P40")
		)
		(pad "B18" smd rect
			(at -22.800056 -0.7747 180)
			(size 0.5588 2.3114)
			(drill
				(offset 0 -0.381)
			)
			(layers "F.Cu" "F.Mask" "F.Paste")
			(net "GND")
		)
		(pad "B19" smd rect
			(at -21.999956 -0.7747 180)
			(size 0.5588 2.3114)
			(drill
				(offset 0 -0.381)
			)
			(layers "F.Cu" "F.Mask" "F.Paste")
			(net "GND")
		)
		(pad "B20" smd rect
			(at -21.20011 -0.7747 180)
			(size 0.5588 2.3114)
			(drill
				(offset 0 -0.381)
			)
			(layers "F.Cu" "F.Mask" "F.Paste")
			(net "PCIE_RX_N41")
		)
		(pad "B21" smd rect
			(at -20.40001 -0.7747 180)
			(size 0.5588 2.3114)
			(drill
				(offset 0 -0.381)
			)
			(layers "F.Cu" "F.Mask" "F.Paste")
			(net "PCIE_RX_P41")
		)
		(pad "B22" smd rect
			(at -19.59991 -0.7747 180)
			(size 0.5588 2.3114)
			(drill
				(offset 0 -0.381)
			)
			(layers "F.Cu" "F.Mask" "F.Paste")
			(net "GND")
		)
		(pad "B23" smd rect
			(at -18.800064 -0.7747 180)
			(size 0.5588 2.3114)
			(drill
				(offset 0 -0.381)
			)
			(layers "F.Cu" "F.Mask" "F.Paste")
			(net "GND")
		)
		(pad "B24" smd rect
			(at -17.999964 -0.7747 180)
			(size 0.5588 2.3114)
			(drill
				(offset 0 -0.381)
			)
			(layers "F.Cu" "F.Mask" "F.Paste")
			(net "PCIE_RX_N42")
		)
		(pad "B25" smd rect
			(at -17.200118 -0.7747 180)
			(size 0.5588 2.3114)
			(drill
				(offset 0 -0.381)
			)
			(layers "F.Cu" "F.Mask" "F.Paste")
			(net "PCIE_RX_P42")
		)
		(pad "B26" smd rect
			(at -16.400018 -0.7747 180)
			(size 0.5588 2.3114)
			(drill
				(offset 0 -0.381)
			)
			(layers "F.Cu" "F.Mask" "F.Paste")
			(net "GND")
		)
		(pad "B27" smd rect
			(at -15.599918 -0.7747 180)
			(size 0.5588 2.3114)
			(drill
				(offset 0 -0.381)
			)
			(layers "F.Cu" "F.Mask" "F.Paste")
			(net "GND")
		)
		(pad "B28" smd rect
			(at -14.800072 -0.7747 180)
			(size 0.5588 2.3114)
			(drill
				(offset 0 -0.381)
			)
			(layers "F.Cu" "F.Mask" "F.Paste")
			(net "PCIE_RX_N43")
		)
		(pad "B29" smd rect
			(at -13.999972 -0.7747 180)
			(size 0.5588 2.3114)
			(drill
				(offset 0 -0.381)
			)
			(layers "F.Cu" "F.Mask" "F.Paste")
			(net "PCIE_RX_P43")
		)
		(pad "B30" smd rect
			(at -13.200126 -0.7747 180)
			(size 0.5588 2.3114)
			(drill
				(offset 0 -0.381)
			)
			(layers "F.Cu" "F.Mask" "F.Paste")
			(net "GND")
		)
		(pad "B31" smd rect
			(at -12.400026 -0.7747 180)
			(size 0.5588 2.3114)
			(drill
				(offset 0 -0.381)
			)
			(layers "F.Cu" "F.Mask" "F.Paste")
			(net "GND")
		)
		(pad "B32" smd rect
			(at -11.599926 -0.7747 180)
			(size 0.5588 2.3114)
			(drill
				(offset 0 -0.381)
			)
			(layers "F.Cu" "F.Mask" "F.Paste")
			(net "PCIE_RX_N44")
		)
		(pad "B33" smd rect
			(at -10.80008 -0.7747 180)
			(size 0.5588 2.3114)
			(drill
				(offset 0 -0.381)
			)
			(layers "F.Cu" "F.Mask" "F.Paste")
			(net "PCIE_RX_P44")
		)
		(pad "B34" smd rect
			(at -9.99998 -0.7747 180)
			(size 0.5588 2.3114)
			(drill
				(offset 0 -0.381)
			)
			(layers "F.Cu" "F.Mask" "F.Paste")
			(net "GND")
		)
		(pad "B35" smd rect
			(at -9.19988 -0.7747 180)
			(size 0.5588 2.3114)
			(drill
				(offset 0 -0.381)
			)
			(layers "F.Cu" "F.Mask" "F.Paste")
			(net "GND")
		)
		(pad "B36" smd rect
			(at -8.400034 -0.7747 180)
			(size 0.5588 2.3114)
			(drill
				(offset 0 -0.381)
			)
			(layers "F.Cu" "F.Mask" "F.Paste")
			(net "PCIE_RX_N45")
		)
		(pad "B37" smd rect
			(at -7.599934 -0.7747 180)
			(size 0.5588 2.3114)
			(drill
				(offset 0 -0.381)
			)
			(layers "F.Cu" "F.Mask" "F.Paste")
			(net "PCIE_RX_P45")
		)
		(pad "B38" smd rect
			(at -6.800088 -0.7747 180)
			(size 0.5588 2.3114)
			(drill
				(offset 0 -0.381)
			)
			(layers "F.Cu" "F.Mask" "F.Paste")
			(net "GND")
		)
		(pad "B39" smd rect
			(at -5.999988 -0.7747 180)
			(size 0.5588 2.3114)
			(drill
				(offset 0 -0.381)
			)
			(layers "F.Cu" "F.Mask" "F.Paste")
			(net "GND")
		)
		(pad "B40" smd rect
			(at -5.199888 -0.7747 180)
			(size 0.5588 2.3114)
			(drill
				(offset 0 -0.381)
			)
			(layers "F.Cu" "F.Mask" "F.Paste")
			(net "PCIE_RX_N46")
		)
		(pad "B41" smd rect
			(at -4.400042 -0.7747 180)
			(size 0.5588 2.3114)
			(drill
				(offset 0 -0.381)
			)
			(layers "F.Cu" "F.Mask" "F.Paste")
			(net "PCIE_RX_P46")
		)
		(pad "B42" smd rect
			(at -3.599942 -0.7747 180)
			(size 0.5588 2.3114)
			(drill
				(offset 0 -0.381)
			)
			(layers "F.Cu" "F.Mask" "F.Paste")
			(net "GND")
		)
		(pad "B43" smd rect
			(at -2.800096 -0.7747 180)
			(size 0.5588 2.3114)
			(drill
				(offset 0 -0.381)
			)
			(layers "F.Cu" "F.Mask" "F.Paste")
			(net "SSD_PERST#7_R")
		)
		(pad "B44" smd rect
			(at -1.999996 -0.7747 180)
			(size 0.5588 2.3114)
			(drill
				(offset 0 -0.381)
			)
			(layers "F.Cu" "F.Mask" "F.Paste")
			(net "SSD_PWREN7_R")
		)
		(pad "B45" smd rect
			(at 1.999996 -0.7747 180)
			(size 0.5588 2.3114)
			(drill
				(offset 0 -0.381)
			)
			(layers "F.Cu" "F.Mask" "F.Paste")
			(net "GND")
		)
		(pad "B46" smd rect
			(at 2.800096 -0.7747 180)
			(size 0.5588 2.3114)
			(drill
				(offset 0 -0.381)
			)
			(layers "F.Cu" "F.Mask" "F.Paste")
			(net "PCIE_RX_N47")
		)
		(pad "B47" smd rect
			(at 3.599942 -0.7747 180)
			(size 0.5588 2.3114)
			(drill
				(offset 0 -0.381)
			)
			(layers "F.Cu" "F.Mask" "F.Paste")
			(net "PCIE_RX_P47")
		)
		(pad "B48" smd rect
			(at 4.400042 -0.7747 180)
			(size 0.5588 2.3114)
			(drill
				(offset 0 -0.381)
			)
			(layers "F.Cu" "F.Mask" "F.Paste")
			(net "GND")
		)
		(pad "B49" smd rect
			(at 5.199888 -0.7747 180)
			(size 0.5588 2.3114)
			(drill
				(offset 0 -0.381)
			)
			(layers "F.Cu" "F.Mask" "F.Paste")
			(net "GND")
		)
		(pad "B50" smd rect
			(at 5.999988 -0.7747 180)
			(size 0.5588 2.3114)
			(drill
				(offset 0 -0.381)
			)
			(layers "F.Cu" "F.Mask" "F.Paste")
			(net "PCIE_RX_N48")
		)
		(pad "B51" smd rect
			(at 6.800088 -0.7747 180)
			(size 0.5588 2.3114)
			(drill
				(offset 0 -0.381)
			)
			(layers "F.Cu" "F.Mask" "F.Paste")
			(net "PCIE_RX_P48")
		)
		(pad "B52" smd rect
			(at 7.599934 -0.7747 180)
			(size 0.5588 2.3114)
			(drill
				(offset 0 -0.381)
			)
			(layers "F.Cu" "F.Mask" "F.Paste")
			(net "GND")
		)
		(pad "B53" smd rect
			(at 8.400034 -0.7747 180)
			(size 0.5588 2.3114)
			(drill
				(offset 0 -0.381)
			)
			(layers "F.Cu" "F.Mask" "F.Paste")
			(net "GND")
		)
		(pad "B54" smd rect
			(at 9.19988 -0.7747 180)
			(size 0.5588 2.3114)
			(drill
				(offset 0 -0.381)
			)
			(layers "F.Cu" "F.Mask" "F.Paste")
			(net "PCIE_RX_N49")
		)
		(pad "B55" smd rect
			(at 9.99998 -0.7747 180)
			(size 0.5588 2.3114)
			(drill
				(offset 0 -0.381)
			)
			(layers "F.Cu" "F.Mask" "F.Paste")
			(net "PCIE_RX_P49")
		)
		(pad "B56" smd rect
			(at 10.80008 -0.7747 180)
			(size 0.5588 2.3114)
			(drill
				(offset 0 -0.381)
			)
			(layers "F.Cu" "F.Mask" "F.Paste")
			(net "GND")
		)
		(pad "B57" smd rect
			(at 11.599926 -0.7747 180)
			(size 0.5588 2.3114)
			(drill
				(offset 0 -0.381)
			)
			(layers "F.Cu" "F.Mask" "F.Paste")
			(net "GND")
		)
		(pad "B58" smd rect
			(at 12.400026 -0.7747 180)
			(size 0.5588 2.3114)
			(drill
				(offset 0 -0.381)
			)
			(layers "F.Cu" "F.Mask" "F.Paste")
			(net "PCIE_RX_N50")
		)
		(pad "B59" smd rect
			(at 13.200126 -0.7747 180)
			(size 0.5588 2.3114)
			(drill
				(offset 0 -0.381)
			)
			(layers "F.Cu" "F.Mask" "F.Paste")
			(net "PCIE_RX_P50")
		)
		(pad "B60" smd rect
			(at 13.999972 -0.7747 180)
			(size 0.5588 2.3114)
			(drill
				(offset 0 -0.381)
			)
			(layers "F.Cu" "F.Mask" "F.Paste")
			(net "GND")
		)
		(pad "B61" smd rect
			(at 14.800072 -0.7747 180)
			(size 0.5588 2.3114)
			(drill
				(offset 0 -0.381)
			)
			(layers "F.Cu" "F.Mask" "F.Paste")
			(net "GND")
		)
		(pad "B62" smd rect
			(at 15.599918 -0.7747 180)
			(size 0.5588 2.3114)
			(drill
				(offset 0 -0.381)
			)
			(layers "F.Cu" "F.Mask" "F.Paste")
			(net "PCIE_RX_N51")
		)
		(pad "B63" smd rect
			(at 16.400018 -0.7747 180)
			(size 0.5588 2.3114)
			(drill
				(offset 0 -0.381)
			)
			(layers "F.Cu" "F.Mask" "F.Paste")
			(net "PCIE_RX_P51")
		)
		(pad "B64" smd rect
			(at 17.200118 -0.7747 180)
			(size 0.5588 2.3114)
			(drill
				(offset 0 -0.381)
			)
			(layers "F.Cu" "F.Mask" "F.Paste")
			(net "GND")
		)
		(pad "B65" smd rect
			(at 17.999964 -0.7747 180)
			(size 0.5588 2.3114)
			(drill
				(offset 0 -0.381)
			)
			(layers "F.Cu" "F.Mask" "F.Paste")
			(net "SSD_PWREN11_R")
		)
		(pad "B66" smd rect
			(at 18.800064 -0.7747 180)
			(size 0.5588 2.3114)
			(drill
				(offset 0 -0.381)
			)
			(layers "F.Cu" "F.Mask" "F.Paste")
			(net "SSD_ATNLED#11_R")
		)
		(pad "B67" smd rect
			(at 19.59991 -0.7747 180)
			(size 0.5588 2.3114)
			(drill
				(offset 0 -0.381)
			)
			(layers "F.Cu" "F.Mask" "F.Paste")
			(net "SSD_PRSNT#11_R")
		)
		(pad "B68" smd rect
			(at 20.40001 -0.7747 180)
			(size 0.5588 2.3114)
			(drill
				(offset 0 -0.381)
			)
			(layers "F.Cu" "F.Mask" "F.Paste")
			(net "GND")
		)
		(pad "B69" smd rect
			(at 21.20011 -0.7747 180)
			(size 0.5588 2.3114)
			(drill
				(offset 0 -0.381)
			)
			(layers "F.Cu" "F.Mask" "F.Paste")
			(net "PCIE_RX_N52")
		)
		(pad "B70" smd rect
			(at 21.999956 -0.7747 180)
			(size 0.5588 2.3114)
			(drill
				(offset 0 -0.381)
			)
			(layers "F.Cu" "F.Mask" "F.Paste")
			(net "PCIE_RX_P52")
		)
		(pad "B71" smd rect
			(at 22.800056 -0.7747 180)
			(size 0.5588 2.3114)
			(drill
				(offset 0 -0.381)
			)
			(layers "F.Cu" "F.Mask" "F.Paste")
			(net "GND")
		)
		(pad "B72" smd rect
			(at 23.599902 -0.7747 180)
			(size 0.5588 2.3114)
			(drill
				(offset 0 -0.381)
			)
			(layers "F.Cu" "F.Mask" "F.Paste")
			(net "GND")
		)
		(pad "B73" smd rect
			(at 24.400002 -0.7747 180)
			(size 0.5588 2.3114)
			(drill
				(offset 0 -0.381)
			)
			(layers "F.Cu" "F.Mask" "F.Paste")
			(net "PCIE_RX_N53")
		)
		(pad "B74" smd rect
			(at 25.200102 -0.7747 180)
			(size 0.5588 2.3114)
			(drill
				(offset 0 -0.381)
			)
			(layers "F.Cu" "F.Mask" "F.Paste")
			(net "PCIE_RX_P53")
		)
		(pad "B75" smd rect
			(at 25.999948 -0.7747 180)
			(size 0.5588 2.3114)
			(drill
				(offset 0 -0.381)
			)
			(layers "F.Cu" "F.Mask" "F.Paste")
			(net "GND")
		)
		(pad "B76" smd rect
			(at 26.800048 -0.7747 180)
			(size 0.5588 2.3114)
			(drill
				(offset 0 -0.381)
			)
			(layers "F.Cu" "F.Mask" "F.Paste")
			(net "GND")
		)
		(pad "B77" smd rect
			(at 27.599894 -0.7747 180)
			(size 0.5588 2.3114)
			(drill
				(offset 0 -0.381)
			)
			(layers "F.Cu" "F.Mask" "F.Paste")
			(net "PCIE_RX_N54")
		)
		(pad "B78" smd rect
			(at 28.399994 -0.7747 180)
			(size 0.5588 2.3114)
			(drill
				(offset 0 -0.381)
			)
			(layers "F.Cu" "F.Mask" "F.Paste")
			(net "PCIE_RX_P54")
		)
		(pad "B79" smd rect
			(at 29.200094 -0.7747 180)
			(size 0.5588 2.3114)
			(drill
				(offset 0 -0.381)
			)
			(layers "F.Cu" "F.Mask" "F.Paste")
			(net "GND")
		)
		(pad "B80" smd rect
			(at 29.99994 -0.7747 180)
			(size 0.5588 2.3114)
			(drill
				(offset 0 -0.381)
			)
			(layers "F.Cu" "F.Mask" "F.Paste")
			(net "GND")
		)
		(pad "B81" smd rect
			(at 30.80004 -0.7747 180)
			(size 0.5588 2.3114)
			(drill
				(offset 0 -0.381)
			)
			(layers "F.Cu" "F.Mask" "F.Paste")
			(net "PCIE_RX_N55")
		)
		(pad "B82" smd rect
			(at 31.599886 -0.7747 180)
			(size 0.5588 2.3114)
			(drill
				(offset 0 -0.381)
			)
			(layers "F.Cu" "F.Mask" "F.Paste")
			(net "PCIE_RX_P55")
		)
		(pad "B83" smd rect
			(at 32.399986 -0.7747 180)
			(size 0.5588 2.3114)
			(drill
				(offset 0 -0.381)
			)
			(layers "F.Cu" "F.Mask" "F.Paste")
			(net "GND")
		)
		(pad "B84" smd rect
			(at 33.200086 -0.7747 180)
			(size 0.5588 2.3114)
			(drill
				(offset 0 -0.381)
			)
			(layers "F.Cu" "F.Mask" "F.Paste")
			(net "GND")
		)
		(pad "B85" smd rect
			(at 33.999932 -0.7747 180)
			(size 0.5588 2.3114)
			(drill
				(offset 0 -0.381)
			)
			(layers "F.Cu" "F.Mask" "F.Paste")
			(net "PCIE_RX_N56")
		)
		(pad "B86" smd rect
			(at 34.800032 -0.7747 180)
			(size 0.5588 2.3114)
			(drill
				(offset 0 -0.381)
			)
			(layers "F.Cu" "F.Mask" "F.Paste")
			(net "PCIE_RX_P56")
		)
		(pad "B87" smd rect
			(at 35.599878 -0.7747 180)
			(size 0.5588 2.3114)
			(drill
				(offset 0 -0.381)
			)
			(layers "F.Cu" "F.Mask" "F.Paste")
			(net "GND")
		)
		(pad "B88" smd rect
			(at 36.399978 -0.7747 180)
			(size 0.5588 2.3114)
			(drill
				(offset 0 -0.381)
			)
			(layers "F.Cu" "F.Mask" "F.Paste")
			(net "GND")
		)
		(pad "B89" smd rect
			(at 37.200078 -0.7747 180)
			(size 0.5588 2.3114)
			(drill
				(offset 0 -0.381)
			)
			(layers "F.Cu" "F.Mask" "F.Paste")
			(net "PCIE_RX_N57")
		)
		(pad "B90" smd rect
			(at 37.999924 -0.7747 180)
			(size 0.5588 2.3114)
			(drill
				(offset 0 -0.381)
			)
			(layers "F.Cu" "F.Mask" "F.Paste")
			(net "PCIE_RX_P57")
		)
		(pad "B91" smd rect
			(at 38.800024 -0.7747 180)
			(size 0.5588 2.3114)
			(drill
				(offset 0 -0.381)
			)
			(layers "F.Cu" "F.Mask" "F.Paste")
			(net "GND")
		)
		(pad "B92" smd rect
			(at 39.600124 -0.7747 180)
			(size 0.5588 2.3114)
			(drill
				(offset 0 -0.381)
			)
			(layers "F.Cu" "F.Mask" "F.Paste")
			(net "GND")
		)
		(pad "B93" smd rect
			(at 40.39997 -0.7747 180)
			(size 0.5588 2.3114)
			(drill
				(offset 0 -0.381)
			)
			(layers "F.Cu" "F.Mask" "F.Paste")
			(net "PCIE_RX_N58")
		)
		(pad "B94" smd rect
			(at 41.20007 -0.7747 180)
			(size 0.5588 2.3114)
			(drill
				(offset 0 -0.381)
			)
			(layers "F.Cu" "F.Mask" "F.Paste")
			(net "PCIE_RX_P58")
		)
		(pad "B95" smd rect
			(at 41.999916 -0.7747 180)
			(size 0.5588 2.3114)
			(drill
				(offset 0 -0.381)
			)
			(layers "F.Cu" "F.Mask" "F.Paste")
			(net "GND")
		)
		(pad "B96" smd rect
			(at 42.800016 -0.7747 180)
			(size 0.5588 2.3114)
			(drill
				(offset 0 -0.381)
			)
			(layers "F.Cu" "F.Mask" "F.Paste")
			(net "GND")
		)
		(pad "B97" smd rect
			(at 43.600116 -0.7747 180)
			(size 0.5588 2.3114)
			(drill
				(offset 0 -0.381)
			)
			(layers "F.Cu" "F.Mask" "F.Paste")
			(net "PCIE_RX_N59")
		)
		(pad "B98" smd rect
			(at 44.399962 -0.7747 180)
			(size 0.5588 2.3114)
			(drill
				(offset 0 -0.381)
			)
			(layers "F.Cu" "F.Mask" "F.Paste")
			(net "PCIE_RX_P59")
		)
		(pad "B99" smd rect
			(at 45.200062 -0.7747 180)
			(size 0.5588 2.3114)
			(drill
				(offset 0 -0.381)
			)
			(layers "F.Cu" "F.Mask" "F.Paste")
			(net "GND")
		)
		(pad "B100" smd rect
			(at 45.999908 -0.7747 180)
			(size 0.5588 2.3114)
			(drill
				(offset 0 -0.381)
			)
			(layers "F.Cu" "F.Mask" "F.Paste")
			(net "SSD_PERST#6_R")
		)
	)
)
